FILE_TYPE = CONNECTIVITY;
{Allegro Design Entry HDL 16.6-p007 (v16-6-112F) 10/10/2012}
"PAGE_NUMBER" = 186;
0"NC";
1"P3E_CPU0_PE3_OCP_RXN<15:8>";
2"P3E_CPU0_PE3_OCP_RXP<15:8>";
3"P3E_OCP_CPU0_PE3_C_TXP<15:8>";
4"P3E_OCP_CPU0_PE3_C_TXN<15:8>";
5"GND\g";
6"GND\g";
7"GND\g";
8"P3V3\g";
9"GND\g";
10"P3V3\g";
11"P3V3\g";
12"GND\g";
13"P3V3_STBY\g";
14"P3V3_STBY\g";
15"P5V_STBY\g";
16"P12V_STBY\g";
17"P12V_STBY\g";
18"P3V3_STBY\g";
19"GND\g";
20"P5V_STBY\g";
21"GND\g";
22"FM_MEZZA_PRSNT1_N";
23"RMII_BMC_OCP_RXD0";
24"RMII_BMC_OCP_CRSDV";
25"RST_PCIE_CPU_DEV0_N";
26"FM_OCP_MEZZA_PRES_N";
27"P3E_OCP_CPU0_PE3_C_TXN<8>";
28"P3E_OCP_CPU0_PE3_C_TXP<8>";
29"P3E_OCP_CPU0_PE3_C_TXN<9>";
30"P3E_OCP_CPU0_PE3_C_TXP<9>";
31"P3E_OCP_CPU0_PE3_C_TXN<10>";
32"P3E_OCP_CPU0_PE3_C_TXP<10>";
33"P3E_OCP_CPU0_PE3_C_TXP<11>";
34"P3E_OCP_CPU0_PE3_C_TXN<11>";
35"P3E_OCP_CPU0_PE3_C_TXN<12>";
36"P3E_OCP_CPU0_PE3_C_TXP<12>";
37"P3E_OCP_CPU0_PE3_C_TXN<13>";
38"P3E_OCP_CPU0_PE3_C_TXP<13>";
39"P3E_OCP_CPU0_PE3_C_TXN<14>";
40"P3E_OCP_CPU0_PE3_C_TXP<14>";
41"P3E_OCP_CPU0_PE3_C_TXN<15>";
42"P3E_OCP_CPU0_PE3_C_TXP<15>";
43"CLK_100M_MEZZ1_DN";
44"CLK_100M_MEZZ1_DP";
45"RMII_BMC_OCP_TXD1";
46"RMII_BMC_OCP_TXD0";
47"RMII_BMC_OCP_RXER_R";
48"SMB_OCP_FRU_STBY_LVC3_SDA";
49"FM_PE_OCP_WAKE_N";
50"SMB_OCP_FRU_STBY_LVC3_SCL";
51"IRQ_MEZZ_LAN_ALERT_N";
52"P3E_CPU0_PE3_OCP_RXN<8>";
53"P3E_CPU0_PE3_OCP_RXP<8>";
54"P3E_CPU0_PE3_OCP_RXN<9>";
55"P3E_CPU0_PE3_OCP_RXP<9>";
56"P3E_CPU0_PE3_OCP_RXN<10>";
57"P3E_CPU0_PE3_OCP_RXP<10>";
58"P3E_CPU0_PE3_OCP_RXN<11>";
59"P3E_CPU0_PE3_OCP_RXP<11>";
60"P3E_CPU0_PE3_OCP_RXN<12>";
61"P3E_CPU0_PE3_OCP_RXP<12>";
62"P3E_CPU0_PE3_OCP_RXN<13>";
63"P3E_CPU0_PE3_OCP_RXP<13>";
64"P3E_CPU0_PE3_OCP_RXN<14>";
65"P3E_CPU0_PE3_OCP_RXP<14>";
66"CLK_100M_MEZZ2_DP";
67"CLK_100M_MEZZ2_DN";
68"RMII_BMC_OCP_RXD1_R";
69"SMB_OCP_LAN_STBY_LVC3_SDA";
70"SMB_OCP_LAN_STBY_LVC3_SCL";
71"RMII_BMC_OCP_TXEN";
72"RST_PCIE_CPU_DEV0_R_N";
73"CLK_50M_CKMNG_OCP";
74"RMII_BMC_OCP_CRSDV_R";
75"RMII_BMC_OCP_RXER";
76"P3E_CPU0_PE3_OCP_RXN<15>";
77"P3E_CPU0_PE3_OCP_RXP<15>";
78"RMII_BMC_OCP_RXD1";
79"RMII_BMC_OCP_RXD0_R";
%"CAP_A"
"1","(10850,4675)","0","dev_discrete","I10";
;
ROOM"IO_SLOT"
SEC"1"
SEC_TYPE"0402V"
CDS_SEC"1"
CDS_LIB"dev_discrete"
CDS_LOCATION"C1M24"
LOCATION"C1M24"
PART_NUMBER"A36096-030"
VALUE"0.1UF"
TOLERANCE"10%"
PACK_TYPE"0402V"
VOLTAGE"16V"
MATERIAL"X7R";
"B"
$PN"2"21;
"A"
$PN"1"11;
%"GND"
"1","(11650,3550)","0","mstr_symbols","I14";
;
VOLTAGE"0"
HDL_POWER"GND"
BODY_TYPE"PLUMBING"
SIZE"1B"
CDS_LIB"mstr_symbols";
"A\NAC"5;
%"GND"
"1","(7525,700)","0","mstr_symbols","I192";
;
VOLTAGE"0"
HDL_POWER"GND"
BODY_TYPE"PLUMBING"
SIZE"1B"
CDS_LIB"mstr_symbols";
"A\NAC"6;
%"GND"
"1","(8975,725)","0","mstr_symbols","I193";
;
VOLTAGE"0"
HDL_POWER"GND"
BODY_TYPE"PLUMBING"
CDS_LIB"mstr_symbols"
SIZE"1B";
"A\NAC"7;
%"P3V3"
"1","(7050,4050)","0","mstr_symbols","I195";
;
VOLTAGE"+3.3"
HDL_POWER"P3V3"
BODY_TYPE"PLUMBING"
SIZE"1B"
CDS_LIB"mstr_symbols";
"G\NAC"8;
%"RES"
"1","(6000,3050)","0","mstr_discrete","I220";
;
CDS_SEC"1"
ROOM"IO_SLOT"
CDS_LOCATION"R1M14"
SEC"1"
CDS_LIB"mstr_discrete"
SEC_TYPE"0402"
MATERIAL"CHIP"
LOCATION"R1M14"
PART_NUMBER"G21796-004"
VALUE"200.0"
TOLERANCE"1%"
PACK_TYPE"0402"
WATTAGE"1/16W";
"B"
$PN"2"72;
"A"
$PN"1"25;
%"RES"
"1","(6500,3850)","0","mstr_discrete","I222";
;
CDS_SEC"1"
ROOM"IO_SLOT"
CDS_LOCATION"R9B7"
SEC"1"
CDS_LIB"mstr_discrete"
SEC_TYPE"0402"
LOCATION"R9B7"
PART_NUMBER"G21796-017"
VALUE"100.0"
TOLERANCE"1%"
PACK_TYPE"0402"
MATERIAL"CHIP"
WATTAGE"1/16W";
"B"
$PN"2"22;
"A"
$PN"1"9;
%"GND"
"1","(6325,3625)","0","mstr_symbols","I223";
;
VOLTAGE"0"
HDL_POWER"GND"
BODY_TYPE"PLUMBING"
SIZE"1B"
CDS_LIB"mstr_symbols";
"A\NAC"9;
%"P3V3"
"1","(8850,4050)","0","mstr_symbols","I247";
;
VOLTAGE"+3.3"
HDL_POWER"P3V3"
BODY_TYPE"PLUMBING"
SIZE"1B"
CDS_LIB"mstr_symbols";
"G\NAC"10;
%"P3V3"
"1","(10450,4950)","0","mstr_symbols","I268";
;
VOLTAGE"+3.3"
HDL_POWER"P3V3"
BODY_TYPE"PLUMBING"
CDS_LIB"mstr_symbols"
SIZE"1B";
"G\NAC"11;
%"GND"
"1","(11650,4275)","0","mstr_symbols","I269";
;
VOLTAGE"0"
HDL_POWER"GND"
SIZE"1B"
BODY_TYPE"PLUMBING"
CDS_LIB"mstr_symbols";
"A\NAC"12;
%"CAP_A"
"1","(11650,4675)","0","dev_discrete","I270";
;
ROOM"IO_SLOT"
$SEC"1"
CDS_LOCATION"C1M20"
CDS_LIB"dev_discrete"
CDS_SEC"1"
LOCATION"C1M20"
PART_NUMBER"A36096-030"
VALUE"0.1UF"
TOLERANCE"10%"
PACK_TYPE"0402V"
VOLTAGE"16V"
MATERIAL"X7R";
"B"
$PN"2"12;
"A"
$PN"1"18;
%"P3V3_STBY"
"1","(7375,4025)","0","mstr_symbols","I274";
;
VOLTAGE"3.3V"
HDL_POWER"P3V3_STBY"
BODY_TYPE"PLUMBING"
SIZE"1B"
CDS_LIB"mstr_symbols";
"G\NAC"13;
%"P3V3_STBY"
"1","(8725,4200)","0","mstr_symbols","I275";
;
VOLTAGE"3.3V"
HDL_POWER"P3V3_STBY"
BODY_TYPE"PLUMBING"
CDS_LIB"mstr_symbols"
SIZE"1B";
"G\NAC"14;
%"P5V_STBY"
"1","(7650,4050)","0","mstr_symbols","I276";
;
VOLTAGE"5.0V"
HDL_POWER"P5V_STBY"
SIZE"1B"
BODY_TYPE"PLUMBING"
CDS_LIB"mstr_symbols";
"G\NAC"15;
%"P12V_STBY"
"1","(9200,4225)","0","mstr_symbols","I278";
;
SIZE"1B"
CDS_LIB"mstr_symbols"
BODY_TYPE"PLUMBING"
HDL_POWER"P12V_STBY"
VOLTAGE"12.0V";
"G\NAC"16;
%"P12V_STBY"
"1","(10450,4225)","0","mstr_symbols","I279";
;
VOLTAGE"12.0V"
HDL_POWER"P12V_STBY"
BODY_TYPE"PLUMBING"
CDS_LIB"mstr_symbols"
SIZE"1B";
"G\NAC"17;
%"P3V3_STBY"
"1","(11250,4950)","0","mstr_symbols","I296";
;
VOLTAGE"3.3V"
HDL_POWER"P3V3_STBY"
BODY_TYPE"PLUMBING"
CDS_LIB"mstr_symbols"
SIZE"1B";
"G\NAC"18;
%"TAP"
"1","(6250,1750)","2","mstr_standard","I297";
;
HDL_TAP"TRUE"
BODY_TYPE"PLUMBING"
CDS_LIB"mstr_standard";
"B \NAC \NWC"1;
"S \NAC"
BN"12"60;
%"TAP"
"1","(6250,1550)","2","mstr_standard","I298";
;
HDL_TAP"TRUE"
BODY_TYPE"PLUMBING"
CDS_LIB"mstr_standard";
"B \NAC \NWC"1;
"S \NAC"
BN"11"58;
%"TAP"
"1","(6250,1350)","2","mstr_standard","I299";
;
HDL_TAP"TRUE"
BODY_TYPE"PLUMBING"
CDS_LIB"mstr_standard";
"B \NAC \NWC"1;
"S \NAC"
BN"10"56;
%"CAP"
"1","(10450,3975)","0","mstr_discrete","I3";
;
CDS_SEC"1"
ROOM"IO_SLOT"
CDS_LOCATION"C1M27"
SEC"1"
CDS_LIB"mstr_discrete"
SEC_TYPE"0805"
LOCATION"C1M27"
PART_NUMBER"C95333-007"
VALUE"10UF"
TOLERANCE"10%"
PACK_TYPE"0805"
VOLTAGE"16V"
MATERIAL"X6S";
"A"
$PN"1"17;
"B"
$PN"2"5;
%"TAP"
"1","(6425,1000)","2","mstr_standard","I300";
;
HDL_TAP"TRUE"
BODY_TYPE"PLUMBING"
CDS_LIB"mstr_standard";
"B \NAC \NWC"2;
"S \NAC"
BN"8"53;
%"TAP"
"1","(6425,2200)","2","mstr_standard","I301";
;
HDL_TAP"TRUE"
BODY_TYPE"PLUMBING"
CDS_LIB"mstr_standard";
"B \NAC \NWC"2;
"S \NAC"
BN"14"65;
%"TAP"
"1","(6425,2400)","2","mstr_standard","I302";
;
HDL_TAP"TRUE"
BODY_TYPE"PLUMBING"
CDS_LIB"mstr_standard";
"B \NAC \NWC"2;
"S \NAC"
BN"15"77;
%"TAP"
"1","(6250,2350)","2","mstr_standard","I303";
;
HDL_TAP"TRUE"
BODY_TYPE"PLUMBING"
CDS_LIB"mstr_standard";
"B \NAC \NWC"1;
"S \NAC"
BN"15"76;
%"TAP"
"1","(6425,2000)","2","mstr_standard","I304";
;
HDL_TAP"TRUE"
BODY_TYPE"PLUMBING"
CDS_LIB"mstr_standard";
"B \NAC \NWC"2;
"S \NAC"
BN"13"63;
%"TAP"
"1","(6425,1800)","2","mstr_standard","I305";
;
HDL_TAP"TRUE"
BODY_TYPE"PLUMBING"
CDS_LIB"mstr_standard";
"B \NAC \NWC"2;
"S \NAC"
BN"12"61;
%"TAP"
"1","(6250,2150)","2","mstr_standard","I306";
;
HDL_TAP"TRUE"
BODY_TYPE"PLUMBING"
CDS_LIB"mstr_standard";
"B \NAC \NWC"1;
"S \NAC"
BN"14"64;
%"TAP"
"1","(6250,1950)","2","mstr_standard","I307";
;
HDL_TAP"TRUE"
BODY_TYPE"PLUMBING"
CDS_LIB"mstr_standard";
"B \NAC \NWC"1;
"S \NAC"
BN"13"62;
%"TAP"
"1","(6425,1600)","2","mstr_standard","I308";
;
HDL_TAP"TRUE"
BODY_TYPE"PLUMBING"
CDS_LIB"mstr_standard";
"B \NAC \NWC"2;
"S \NAC"
BN"11"59;
%"TAP"
"1","(6425,1400)","2","mstr_standard","I309";
;
HDL_TAP"TRUE"
BODY_TYPE"PLUMBING"
CDS_LIB"mstr_standard";
"B \NAC \NWC"2;
"S \NAC"
BN"10"57;
%"TAP"
"1","(6425,1200)","2","mstr_standard","I310";
;
HDL_TAP"TRUE"
BODY_TYPE"PLUMBING"
CDS_LIB"mstr_standard";
"B \NAC \NWC"2;
"S \NAC"
BN"9"55;
%"TAP"
"1","(6250,1150)","2","mstr_standard","I311";
;
HDL_TAP"TRUE"
BODY_TYPE"PLUMBING"
CDS_LIB"mstr_standard";
"B \NAC \NWC"1;
"S \NAC"
BN"9"54;
%"TAP"
"1","(6250,950)","2","mstr_standard","I312";
;
HDL_TAP"TRUE"
BODY_TYPE"PLUMBING"
CDS_LIB"mstr_standard";
"B \NAC \NWC"1;
"S \NAC"
BN"8"52;
%"TAP"
"1","(10250,1850)","0","mstr_standard","I315";
;
HDL_TAP"TRUE"
BODY_TYPE"PLUMBING"
CDS_LIB"mstr_standard";
"B \NAC \NWC"4;
"S \NAC"
BN"12"35;
%"TAP"
"1","(10050,2100)","0","mstr_standard","I316";
;
HDL_TAP"TRUE"
BODY_TYPE"PLUMBING"
CDS_LIB"mstr_standard";
"B \NAC \NWC"3;
"S \NAC"
BN"13"38;
%"TAP"
"1","(10050,2300)","0","mstr_standard","I317";
;
HDL_TAP"TRUE"
BODY_TYPE"PLUMBING"
CDS_LIB"mstr_standard";
"B \NAC \NWC"3;
"S \NAC"
BN"14"40;
%"TAP"
"1","(10050,2500)","0","mstr_standard","I318";
;
HDL_TAP"TRUE"
BODY_TYPE"PLUMBING"
CDS_LIB"mstr_standard";
"B \NAC \NWC"3;
"S \NAC"
BN"15"42;
%"TAP"
"1","(10250,2450)","0","mstr_standard","I321";
;
HDL_TAP"TRUE"
BODY_TYPE"PLUMBING"
CDS_LIB"mstr_standard";
"B \NAC \NWC"4;
"S \NAC"
BN"15"41;
%"TAP"
"1","(10250,2250)","0","mstr_standard","I322";
;
HDL_TAP"TRUE"
BODY_TYPE"PLUMBING"
CDS_LIB"mstr_standard";
"B \NAC \NWC"4;
"S \NAC"
BN"14"39;
%"TAP"
"1","(10250,2050)","0","mstr_standard","I323";
;
HDL_TAP"TRUE"
BODY_TYPE"PLUMBING"
CDS_LIB"mstr_standard";
"B \NAC \NWC"4;
"S \NAC"
BN"13"37;
%"TAP"
"1","(10250,1650)","0","mstr_standard","I324";
;
HDL_TAP"TRUE"
BODY_TYPE"PLUMBING"
CDS_LIB"mstr_standard";
"B \NAC \NWC"4;
"S \NAC"
BN"11"34;
%"TAP"
"1","(10050,1700)","0","mstr_standard","I325";
;
HDL_TAP"TRUE"
BODY_TYPE"PLUMBING"
CDS_LIB"mstr_standard";
"B \NAC \NWC"3;
"S \NAC"
BN"11"33;
%"TAP"
"1","(10050,1900)","0","mstr_standard","I326";
;
HDL_TAP"TRUE"
BODY_TYPE"PLUMBING"
CDS_LIB"mstr_standard";
"B \NAC \NWC"3;
"S \NAC"
BN"12"36;
%"TAP"
"1","(10250,1450)","0","mstr_standard","I327";
;
HDL_TAP"TRUE"
BODY_TYPE"PLUMBING"
CDS_LIB"mstr_standard";
"B \NAC \NWC"4;
"S \NAC"
BN"10"31;
%"TAP"
"1","(10250,1250)","0","mstr_standard","I328";
;
HDL_TAP"TRUE"
BODY_TYPE"PLUMBING"
CDS_LIB"mstr_standard";
"B \NAC \NWC"4;
"S \NAC"
BN"9"29;
%"TAP"
"1","(10050,1300)","0","mstr_standard","I329";
;
HDL_TAP"TRUE"
BODY_TYPE"PLUMBING"
CDS_LIB"mstr_standard";
"B \NAC \NWC"3;
"S \NAC"
BN"9"30;
%"TAP"
"1","(10050,1500)","0","mstr_standard","I330";
;
HDL_TAP"TRUE"
BODY_TYPE"PLUMBING"
CDS_LIB"mstr_standard";
"B \NAC \NWC"3;
"S \NAC"
BN"10"32;
%"TAP"
"1","(10250,1050)","0","mstr_standard","I331";
;
HDL_TAP"TRUE"
BODY_TYPE"PLUMBING"
CDS_LIB"mstr_standard";
"B \NAC \NWC"4;
"S \NAC"
BN"8"27;
%"TAP"
"1","(10050,1100)","0","mstr_standard","I332";
;
HDL_TAP"TRUE"
BODY_TYPE"PLUMBING"
CDS_LIB"mstr_standard";
"B \NAC \NWC"3;
"S \NAC"
BN"8"28;
%"CAP_A"
"1","(10450,4700)","0","dev_discrete","I334";
;
ROOM"IO_SLOT"
SEC"1"
SEC_TYPE"0402V"
CDS_SEC"1"
CDS_LIB"dev_discrete"
CDS_LOCATION"C1M21"
LOCATION"C1M21"
PART_NUMBER"D97712-004"
VALUE"1.0UF"
TOLERANCE"10%"
PACK_TYPE"0402V"
VOLTAGE"6.3V"
MATERIAL"X6S";
"B"
$PN"2"21;
"A"
$PN"1"11;
%"CAP_A"
"1","(11250,4700)","0","dev_discrete","I335";
;
ROOM"IO_SLOT"
SEC_TYPE"0402V"
SEC"1"
CDS_LOCATION"C1M25"
CDS_LIB"dev_discrete"
CDS_SEC"1"
LOCATION"C1M25"
PART_NUMBER"D97712-004"
VALUE"1.0UF"
TOLERANCE"10%"
PACK_TYPE"0402V"
VOLTAGE"6.3V"
MATERIAL"X6S";
"B"
$PN"2"12;
"A"
$PN"1"18;
%"SCONN120_A28699018"
"1","(8250,2350)","0","mstr_sconn","I336";
;
CDS_SEC"1"
CDS_LIB"mstr_sconn"
SEC_TYPE"SM"
SEC"1"
CDS_LOCATION"J9B3"
ROOM"IO_SLOT"
PACK_TYPE"SM"
MATERIAL"SCONN"
PART_NUMBER"A28699-018"
LOCATION"J9B3";
"IO1"
$PN"1"22;
"IO3"
$PN"3"15;
"IO120"
$PN"120"26;
"IO118"
$PN"118"7;
"IO114"
$PN"114"27;
"IO116"
$PN"116"7;
"IO112"
$PN"112"28;
"IO110"
$PN"110"7;
"IO108"
$PN"108"7;
"IO106"
$PN"106"29;
"IO104"
$PN"104"30;
"IO102"
$PN"102"7;
"IO100"
$PN"100"7;
"IO98"
$PN"98"31;
"IO94"
$PN"94"7;
"IO96"
$PN"96"32;
"IO88"
$PN"88"33;
"IO90"
$PN"90"34;
"IO92"
$PN"92"7;
"IO86"
$PN"86"7;
"IO84"
$PN"84"7;
"IO82"
$PN"82"35;
"IO78"
$PN"78"7;
"IO80"
$PN"80"36;
"IO74"
$PN"74"37;
"IO76"
$PN"76"7;
"IO72"
$PN"72"38;
"IO70"
$PN"70"7;
"IO68"
$PN"68"7;
"IO66"
$PN"66"39;
"IO64"
$PN"64"40;
"IO62"
$PN"62"7;
"IO58"
$PN"58"41;
"IO60"
$PN"60"7;
"IO52"
$PN"52"7;
"IO54"
$PN"54"7;
"IO56"
$PN"56"42;
"IO50"
$PN"50"43;
"IO48"
$PN"48"44;
"IO46"
$PN"46"7;
"IO44"
$PN"44"7;
"IO42"
$PN"42"45;
"IO38"
$PN"38"7;
"IO40"
$PN"40"46;
"IO36"
$PN"36"47;
"IO32"
$PN"32"48;
"IO34"
$PN"34"49;
"IO30"
$PN"30"50;
"IO28"
$PN"28"51;
"IO26"
$PN"26"7;
"IO24"
$PN"24"10;
"IO22"
$PN"22"10;
"IO16"
$PN"16"7;
"IO18"
$PN"18"10;
"IO20"
$PN"20"10;
"IO14"
$PN"14"7;
"IO12"
$PN"12"14;
"IO8"
$PN"8"7;
"IO10"
$PN"10"7;
"IO6"
$PN"6"16;
"IO2"
$PN"2"16;
"IO4"
$PN"4"16;
"IO119"
$PN"119"6;
"IO117"
$PN"117"52;
"IO113"
$PN"113"6;
"IO115"
$PN"115"53;
"IO111"
$PN"111"6;
"IO109"
$PN"109"54;
"IO107"
$PN"107"55;
"IO105"
$PN"105"6;
"IO103"
$PN"103"6;
"IO101"
$PN"101"56;
"IO97"
$PN"97"6;
"IO99"
$PN"99"57;
"IO93"
$PN"93"58;
"IO95"
$PN"95"6;
"IO89"
$PN"89"6;
"IO87"
$PN"87"6;
"IO91"
$PN"91"59;
"IO85"
$PN"85"60;
"IO83"
$PN"83"61;
"IO81"
$PN"81"6;
"IO77"
$PN"77"62;
"IO79"
$PN"79"6;
"IO73"
$PN"73"6;
"IO75"
$PN"75"63;
"IO71"
$PN"71"6;
"IO69"
$PN"69"64;
"IO67"
$PN"67"65;
"IO65"
$PN"65"6;
"IO63"
$PN"63"6;
"IO61"
$PN"61"76;
"IO57"
$PN"57"6;
"IO59"
$PN"59"77;
"IO51"
$PN"51"66;
"IO53"
$PN"53"67;
"IO55"
$PN"55"6;
"IO49"
$PN"49"6;
"IO47"
$PN"47"6;
"IO45"
$PN"45"68;
"IO43"
$PN"43"79;
"IO41"
$PN"41"6;
"IO37"
$PN"37"69;
"IO39"
$PN"39"6;
"IO35"
$PN"35"70;
"IO31"
$PN"31"71;
"IO33"
$PN"33"72;
"IO29"
$PN"29"73;
"IO27"
$PN"27"74;
"IO25"
$PN"25"8;
"IO23"
$PN"23"8;
"IO21"
$PN"21"8;
"IO15"
$PN"15"6;
"IO17"
$PN"17"6;
"IO19"
$PN"19"8;
"IO13"
$PN"13"13;
"IO11"
$PN"11"6;
"IO9"
$PN"9"6;
"IO7"
$PN"7"15;
"IO5"
$PN"5"15;
%"RES"
"1","(6700,2750)","0","mstr_discrete","I337";
;
CDS_SEC"1"
PACK_TYPE"0402"
MATERIAL"CHIP"
WATTAGE"1/16W"
ROOM"IO_SLOT"
CDS_LOCATION"R1M16"
SEC"1"
SEC_TYPE"0402"
CDS_LIB"mstr_discrete"
LOCATION"R1M16"
PART_NUMBER"G21497-005"
VALUE"0.0"
TOLERANCE"5%";
"B"
$PN"2"68;
"A"
$PN"1"78;
%"RES"
"1","(6375,2800)","0","mstr_discrete","I338";
;
CDS_SEC"1"
PACK_TYPE"0402"
MATERIAL"CHIP"
WATTAGE"1/16W"
ROOM"IO_SLOT"
CDS_LOCATION"R1M17"
SEC"1"
CDS_LIB"mstr_discrete"
SEC_TYPE"0402"
LOCATION"R1M17"
PART_NUMBER"G21497-005"
VALUE"0.0"
TOLERANCE"5%";
"B"
$PN"2"79;
"A"
$PN"1"23;
%"RES"
"1","(6375,3200)","0","mstr_discrete","I339";
;
CDS_SEC"1"
PACK_TYPE"0402"
MATERIAL"CHIP"
WATTAGE"1/16W"
ROOM"IO_SLOT"
CDS_LOCATION"R1M15"
SEC"1"
CDS_LIB"mstr_discrete"
SEC_TYPE"0402"
LOCATION"R1M15"
PART_NUMBER"G21497-005"
VALUE"0.0"
TOLERANCE"5%";
"B"
$PN"2"74;
"A"
$PN"1"24;
%"RES"
"1","(10250,3000)","0","mstr_discrete","I340";
;
CDS_SEC"1"
PACK_TYPE"0402"
MATERIAL"CHIP"
WATTAGE"1/16W"
ROOM"IO_SLOT"
CDS_LOCATION"R1M18"
SEC"1"
CDS_LIB"mstr_discrete"
SEC_TYPE"0402"
LOCATION"R1M18"
PART_NUMBER"G21497-005"
VALUE"0.0"
TOLERANCE"5%";
"B"
$PN"2"75;
"A"
$PN"1"47;
%"CAP_A"
"1","(10050,3950)","0","dev_discrete","I345";
;
CDS_SEC"1"
CDS_LOCATION"C9B10"
ROOM"IO_SLOT"
SEC_TYPE"0402V"
SEC"1"
CDS_LIB"dev_discrete"
PART_NUMBER"A36096-030"
VALUE"0.1UF"
TOLERANCE"10%"
PACK_TYPE"0402V"
VOLTAGE"16V"
MATERIAL"X7R"
LOCATION"C9B10";
"B"
$PN"2"19;
"A"
$PN"1"20;
%"GND"
"1","(10050,3550)","0","mstr_symbols","I346";
;
VOLTAGE"0"
HDL_POWER"GND"
CDS_LIB"mstr_symbols"
BODY_TYPE"PLUMBING"
SIZE"1B";
"A\NAC"19;
%"CAP_A"
"1","(9650,3950)","0","dev_discrete","I347";
;
CDS_SEC"1"
CDS_LOCATION"C9B9"
ROOM"IO_SLOT"
SEC"1"
SEC_TYPE"0402V"
CDS_LIB"dev_discrete"
PACK_TYPE"0402V"
VALUE"1.0UF"
VOLTAGE"6.3V"
PART_NUMBER"D97712-004"
MATERIAL"X6S"
TOLERANCE"10%"
LOCATION"C9B9";
"B"
$PN"2"19;
"A"
$PN"1"20;
%"P5V_STBY"
"1","(9650,4225)","0","mstr_symbols","I348";
;
VOLTAGE"5.0V"
HDL_POWER"P5V_STBY"
CDS_LIB"mstr_symbols"
BODY_TYPE"PLUMBING"
SIZE"1B";
"G\NAC"20;
%"CAP"
"1","(10850,3950)","0","mstr_discrete","I6";
;
CDS_SEC"1"
ROOM"IO_SLOT"
CDS_LOCATION"C1M26"
SEC"1"
CDS_LIB"mstr_discrete"
SEC_TYPE"0805"
LOCATION"C1M26"
PART_NUMBER"C95333-007"
VALUE"10UF"
TOLERANCE"10%"
PACK_TYPE"0805"
VOLTAGE"16V"
MATERIAL"X6S";
"A"
$PN"1"17;
"B"
$PN"2"5;
%"CAP_A"
"1","(11225,3950)","0","dev_discrete","I7";
;
ROOM"IO_SLOT"
SEC"1"
SEC_TYPE"0402V"
CDS_SEC"1"
CDS_LIB"dev_discrete"
CDS_LOCATION"C1M23"
LOCATION"C1M23"
PART_NUMBER"A36096-030"
VALUE"0.1UF"
TOLERANCE"10%"
PACK_TYPE"0402V"
VOLTAGE"16V"
MATERIAL"X7R";
"B"
$PN"2"5;
"A"
$PN"1"17;
%"CAP_A"
"1","(11650,3950)","0","dev_discrete","I8";
;
ROOM"IO_SLOT"
SEC"1"
SEC_TYPE"0402V"
CDS_SEC"1"
CDS_LIB"dev_discrete"
CDS_LOCATION"C1M22"
LOCATION"C1M22"
PART_NUMBER"A36096-030"
VALUE"0.1UF"
TOLERANCE"10%"
PACK_TYPE"0402V"
VOLTAGE"16V"
MATERIAL"X7R";
"B"
$PN"2"5;
"A"
$PN"1"17;
%"GND"
"1","(10850,4275)","0","mstr_symbols","I9";
;
VOLTAGE"0"
HDL_POWER"GND"
BODY_TYPE"PLUMBING"
CDS_LIB"mstr_symbols"
SIZE"1B";
"A\NAC"21;
END.
